(kicad_pcb
	(version 20260206)
	(generator "pcbnew")
	(generator_version "10.0")
	(general
		(thickness 1.6)
		(legacy_teardrops no)
	)
	(paper "A4")
	(title_block
		(title "03242023_DA0F0TMBIJ0_F0T_Motherboard_J_brd_V01_OCP.brd")
		(comment 1 "Grand Teton / footprints 1980-1986 of 6105")
	)
	(layers
		(0 "F.Cu" signal "TOP")
		(4 "In1.Cu" signal "GND")
		(6 "In2.Cu" signal "IN1")
		(8 "In3.Cu" signal "GND1")
		(10 "In4.Cu" signal "IN2")
		(12 "In5.Cu" signal "GND2")
		(14 "In6.Cu" signal "IN3")
		(16 "In7.Cu" signal "GND3")
		(18 "In8.Cu" signal "VCC")
		(20 "In9.Cu" signal "VCC1")
		(22 "In10.Cu" signal "GND4")
		(24 "In11.Cu" signal "IN4")
		(26 "In12.Cu" signal "GND5")
		(28 "In13.Cu" signal "IN5")
		(30 "In14.Cu" signal "GND6")
		(32 "In15.Cu" signal "IN6")
		(34 "In16.Cu" signal "GND7")
		(2 "B.Cu" signal "BOTTOM")
		(9 "F.Adhes" user "F.Adhesive")
		(11 "B.Adhes" user "B.Adhesive")
		(13 "F.Paste" user "Package Geometry/Pastemask Top")
		(15 "B.Paste" user "Package Geometry/Pastemask Bottom")
		(5 "F.SilkS" user "Ref Des/Silkscreen Top")
		(7 "B.SilkS" user "Ref Des/Silkscreen Bottom")
		(1 "F.Mask" user "Board Geometry/Soldermask Top")
		(3 "B.Mask" user "Board Geometry/Soldermask Bottom")
		(17 "Dwgs.User" user "User.Drawings")
		(19 "Cmts.User" user "User.Comments")
		(21 "Eco1.User" user "User.Eco1")
		(23 "Eco2.User" user "User.Eco2")
		(25 "Edge.Cuts" user "Board Geometry/Outline")
		(27 "Margin" user)
		(31 "F.CrtYd" user "Package Geometry/Place Bound Top")
		(29 "B.CrtYd" user "Package Geometry/Place Bound Bottom")
		(35 "F.Fab" user "Ref Des/Assembly Top")
		(33 "B.Fab" user "Ref Des/Assembly Bottom")
	)
	(footprint ""
		(layer "F.Cu")
		(at 128.348486 -342.270334)
		(property "Reference" "PR292"
			(at 0 0 0)
			(layer "F.SilkS")
			(hide yes)
			(effects
				(font
					(size 1.27 1.27)
				)
			)
		)
		(property "Value" ""
			(at 0 0 0)
			(layer "F.Fab")
			(effects
				(font
					(size 1.27 1.27)
				)
			)
		)
		(duplicate_pad_numbers_are_jumpers no)
		(fp_line
			(start -0.7874 -0.4064)
			(end 0.7874 -0.4064)
			(stroke
				(width 0.1524)
				(type default)
			)
			(layer "F.SilkS")
		)
		(fp_line
			(start -0.7874 0.4064)
			(end -0.7874 -0.4064)
			(stroke
				(width 0.1524)
				(type default)
			)
			(layer "F.SilkS")
		)
		(fp_line
			(start 0.7874 -0.4064)
			(end 0.7874 0.4064)
			(stroke
				(width 0.1524)
				(type default)
			)
			(layer "F.SilkS")
		)
		(fp_line
			(start 0.7874 0.4064)
			(end -0.7874 0.4064)
			(stroke
				(width 0.1524)
				(type default)
			)
			(layer "F.SilkS")
		)
		(fp_line
			(start -0.67945 -0.305054)
			(end -0.12065 -0.305054)
			(stroke
				(width 0.1)
				(type default)
			)
			(layer "F.Fab")
		)
		(fp_line
			(start -0.67945 0.3048)
			(end -0.67945 -0.305054)
			(stroke
				(width 0.1)
				(type default)
			)
			(layer "F.Fab")
		)
		(fp_line
			(start -0.12065 -0.305054)
			(end -0.12065 -0.2794)
			(stroke
				(width 0.1)
				(type default)
			)
			(layer "F.Fab")
		)
		(fp_line
			(start -0.12065 -0.2794)
			(end 0.12065 -0.2794)
			(stroke
				(width 0.1)
				(type default)
			)
			(layer "F.Fab")
		)
		(fp_line
			(start -0.12065 0.2794)
			(end -0.12065 0.3048)
			(stroke
				(width 0.1)
				(type default)
			)
			(layer "F.Fab")
		)
		(fp_line
			(start -0.12065 0.3048)
			(end -0.67945 0.3048)
			(stroke
				(width 0.1)
				(type default)
			)
			(layer "F.Fab")
		)
		(fp_line
			(start 0.120396 0.2794)
			(end -0.12065 0.2794)
			(stroke
				(width 0.1)
				(type default)
			)
			(layer "F.Fab")
		)
		(fp_line
			(start 0.120396 0.3048)
			(end 0.120396 0.2794)
			(stroke
				(width 0.1)
				(type default)
			)
			(layer "F.Fab")
		)
		(fp_line
			(start 0.12065 -0.3048)
			(end 0.67945 -0.3048)
			(stroke
				(width 0.1)
				(type default)
			)
			(layer "F.Fab")
		)
		(fp_line
			(start 0.12065 -0.2794)
			(end 0.12065 -0.3048)
			(stroke
				(width 0.1)
				(type default)
			)
			(layer "F.Fab")
		)
		(fp_line
			(start 0.67945 -0.3048)
			(end 0.67945 0.3048)
			(stroke
				(width 0.1)
				(type default)
			)
			(layer "F.Fab")
		)
		(fp_line
			(start 0.67945 0.3048)
			(end 0.120396 0.3048)
			(stroke
				(width 0.1)
				(type default)
			)
			(layer "F.Fab")
		)
		(pad "1" smd circle
			(at -0.40005 0)
			(size 0 0)
			(layers "F.Cu" "F.Mask" "F.Paste")
			(net "PVCCIN_CPU1_LSET5")
		)
		(pad "2" smd circle
			(at 0.40005 0)
			(size 0 0)
			(layers "F.Cu" "F.Mask" "F.Paste")
			(net "GND")
		)
	)
	(footprint ""
		(layer "F.Cu")
		(at 123.62688 -92.674948 -90)
		(property "Reference" "R4399"
			(at 0 0 270)
			(layer "F.SilkS")
			(hide yes)
			(effects
				(font
					(size 1.27 1.27)
				)
			)
		)
		(property "Value" ""
			(at 0 0 270)
			(layer "F.Fab")
			(effects
				(font
					(size 1.27 1.27)
				)
			)
		)
		(duplicate_pad_numbers_are_jumpers no)
		(fp_line
			(start -0.7874 0.4064)
			(end -0.7874 -0.4064)
			(stroke
				(width 0.1524)
				(type default)
			)
			(layer "F.SilkS")
		)
		(fp_line
			(start 0.7874 0.4064)
			(end -0.7874 0.4064)
			(stroke
				(width 0.1524)
				(type default)
			)
			(layer "F.SilkS")
		)
		(fp_line
			(start -0.7874 -0.4064)
			(end 0.7874 -0.4064)
			(stroke
				(width 0.1524)
				(type default)
			)
			(layer "F.SilkS")
		)
		(fp_line
			(start 0.7874 -0.4064)
			(end 0.7874 0.4064)
			(stroke
				(width 0.1524)
				(type default)
			)
			(layer "F.SilkS")
		)
		(fp_line
			(start -0.67945 0.3048)
			(end -0.67945 -0.305054)
			(stroke
				(width 0.1)
				(type default)
			)
			(layer "F.Fab")
		)
		(fp_line
			(start -0.12065 0.3048)
			(end -0.67945 0.3048)
			(stroke
				(width 0.1)
				(type default)
			)
			(layer "F.Fab")
		)
		(fp_line
			(start 0.120396 0.3048)
			(end 0.120396 0.2794)
			(stroke
				(width 0.1)
				(type default)
			)
			(layer "F.Fab")
		)
		(fp_line
			(start 0.67945 0.3048)
			(end 0.120396 0.3048)
			(stroke
				(width 0.1)
				(type default)
			)
			(layer "F.Fab")
		)
		(fp_line
			(start -0.12065 0.2794)
			(end -0.12065 0.3048)
			(stroke
				(width 0.1)
				(type default)
			)
			(layer "F.Fab")
		)
		(fp_line
			(start 0.120396 0.2794)
			(end -0.12065 0.2794)
			(stroke
				(width 0.1)
				(type default)
			)
			(layer "F.Fab")
		)
		(fp_line
			(start -0.12065 -0.2794)
			(end 0.12065 -0.2794)
			(stroke
				(width 0.1)
				(type default)
			)
			(layer "F.Fab")
		)
		(fp_line
			(start 0.12065 -0.2794)
			(end 0.12065 -0.3048)
			(stroke
				(width 0.1)
				(type default)
			)
			(layer "F.Fab")
		)
		(fp_line
			(start 0.12065 -0.3048)
			(end 0.67945 -0.3048)
			(stroke
				(width 0.1)
				(type default)
			)
			(layer "F.Fab")
		)
		(fp_line
			(start 0.67945 -0.3048)
			(end 0.67945 0.3048)
			(stroke
				(width 0.1)
				(type default)
			)
			(layer "F.Fab")
		)
		(fp_line
			(start -0.67945 -0.305054)
			(end -0.12065 -0.305054)
			(stroke
				(width 0.1)
				(type default)
			)
			(layer "F.Fab")
		)
		(fp_line
			(start -0.12065 -0.305054)
			(end -0.12065 -0.2794)
			(stroke
				(width 0.1)
				(type default)
			)
			(layer "F.Fab")
		)
		(pad "1" smd circle
			(at -0.40005 0 270)
			(size 0 0)
			(layers "F.Cu" "F.Mask" "F.Paste")
			(net "H_CPU0_THERMTRIP_VT_N")
		)
		(pad "2" smd circle
			(at 0.40005 0 270)
			(size 0 0)
			(layers "F.Cu" "F.Mask" "F.Paste")
			(net "H_CPU0_THERMTRIP_LVC1_N")
		)
	)
	(footprint ""
		(layer "F.Cu")
		(at 213.41588 -50.637948 90)
		(property "Reference" "R3756"
			(at 0 0 90)
			(layer "F.SilkS")
			(hide yes)
			(effects
				(font
					(size 1.27 1.27)
				)
			)
		)
		(property "Value" ""
			(at 0 0 90)
			(layer "F.Fab")
			(effects
				(font
					(size 1.27 1.27)
				)
			)
		)
		(duplicate_pad_numbers_are_jumpers no)
		(fp_line
			(start 0.7874 -0.4064)
			(end 0.7874 0.4064)
			(stroke
				(width 0.1524)
				(type default)
			)
			(layer "F.SilkS")
		)
		(fp_line
			(start -0.7874 -0.4064)
			(end 0.7874 -0.4064)
			(stroke
				(width 0.1524)
				(type default)
			)
			(layer "F.SilkS")
		)
		(fp_line
			(start 0.7874 0.4064)
			(end -0.7874 0.4064)
			(stroke
				(width 0.1524)
				(type default)
			)
			(layer "F.SilkS")
		)
		(fp_line
			(start -0.7874 0.4064)
			(end -0.7874 -0.4064)
			(stroke
				(width 0.1524)
				(type default)
			)
			(layer "F.SilkS")
		)
		(fp_line
			(start -0.12065 -0.305054)
			(end -0.12065 -0.2794)
			(stroke
				(width 0.1)
				(type default)
			)
			(layer "F.Fab")
		)
		(fp_line
			(start -0.67945 -0.305054)
			(end -0.12065 -0.305054)
			(stroke
				(width 0.1)
				(type default)
			)
			(layer "F.Fab")
		)
		(fp_line
			(start 0.67945 -0.3048)
			(end 0.67945 0.3048)
			(stroke
				(width 0.1)
				(type default)
			)
			(layer "F.Fab")
		)
		(fp_line
			(start 0.12065 -0.3048)
			(end 0.67945 -0.3048)
			(stroke
				(width 0.1)
				(type default)
			)
			(layer "F.Fab")
		)
		(fp_line
			(start 0.12065 -0.2794)
			(end 0.12065 -0.3048)
			(stroke
				(width 0.1)
				(type default)
			)
			(layer "F.Fab")
		)
		(fp_line
			(start -0.12065 -0.2794)
			(end 0.12065 -0.2794)
			(stroke
				(width 0.1)
				(type default)
			)
			(layer "F.Fab")
		)
		(fp_line
			(start 0.120396 0.2794)
			(end -0.12065 0.2794)
			(stroke
				(width 0.1)
				(type default)
			)
			(layer "F.Fab")
		)
		(fp_line
			(start -0.12065 0.2794)
			(end -0.12065 0.3048)
			(stroke
				(width 0.1)
				(type default)
			)
			(layer "F.Fab")
		)
		(fp_line
			(start 0.67945 0.3048)
			(end 0.120396 0.3048)
			(stroke
				(width 0.1)
				(type default)
			)
			(layer "F.Fab")
		)
		(fp_line
			(start 0.120396 0.3048)
			(end 0.120396 0.2794)
			(stroke
				(width 0.1)
				(type default)
			)
			(layer "F.Fab")
		)
		(fp_line
			(start -0.12065 0.3048)
			(end -0.67945 0.3048)
			(stroke
				(width 0.1)
				(type default)
			)
			(layer "F.Fab")
		)
		(fp_line
			(start -0.67945 0.3048)
			(end -0.67945 -0.305054)
			(stroke
				(width 0.1)
				(type default)
			)
			(layer "F.Fab")
		)
		(pad "1" smd circle
			(at -0.40005 0 90)
			(size 0 0)
			(layers "F.Cu" "F.Mask" "F.Paste")
			(net "SMB_INA230_2_3V3AUX_SDA_R")
		)
		(pad "2" smd circle
			(at 0.40005 0 90)
			(size 0 0)
			(layers "F.Cu" "F.Mask" "F.Paste")
			(net "SMB_INA230_2_3V3AUX_SDA_R1")
		)
	)
	(footprint ""
		(layer "F.Cu")
		(at 71.393558 -65.082674 -90)
		(property "Reference" "R3082"
			(at 0 0 270)
			(layer "F.SilkS")
			(hide yes)
			(effects
				(font
					(size 1.27 1.27)
				)
			)
		)
		(property "Value" ""
			(at 0 0 270)
			(layer "F.Fab")
			(effects
				(font
					(size 1.27 1.27)
				)
			)
		)
		(duplicate_pad_numbers_are_jumpers no)
		(fp_line
			(start -0.7874 0.4064)
			(end -0.7874 -0.4064)
			(stroke
				(width 0.1524)
				(type default)
			)
			(layer "F.SilkS")
		)
		(fp_line
			(start 0.7874 0.4064)
			(end -0.7874 0.4064)
			(stroke
				(width 0.1524)
				(type default)
			)
			(layer "F.SilkS")
		)
		(fp_line
			(start -0.7874 -0.4064)
			(end 0.7874 -0.4064)
			(stroke
				(width 0.1524)
				(type default)
			)
			(layer "F.SilkS")
		)
		(fp_line
			(start 0.7874 -0.4064)
			(end 0.7874 0.4064)
			(stroke
				(width 0.1524)
				(type default)
			)
			(layer "F.SilkS")
		)
		(fp_line
			(start -0.67945 0.3048)
			(end -0.67945 -0.305054)
			(stroke
				(width 0.1)
				(type default)
			)
			(layer "F.Fab")
		)
		(fp_line
			(start -0.12065 0.3048)
			(end -0.67945 0.3048)
			(stroke
				(width 0.1)
				(type default)
			)
			(layer "F.Fab")
		)
		(fp_line
			(start 0.120396 0.3048)
			(end 0.120396 0.2794)
			(stroke
				(width 0.1)
				(type default)
			)
			(layer "F.Fab")
		)
		(fp_line
			(start 0.67945 0.3048)
			(end 0.120396 0.3048)
			(stroke
				(width 0.1)
				(type default)
			)
			(layer "F.Fab")
		)
		(fp_line
			(start -0.12065 0.2794)
			(end -0.12065 0.3048)
			(stroke
				(width 0.1)
				(type default)
			)
			(layer "F.Fab")
		)
		(fp_line
			(start 0.120396 0.2794)
			(end -0.12065 0.2794)
			(stroke
				(width 0.1)
				(type default)
			)
			(layer "F.Fab")
		)
		(fp_line
			(start -0.12065 -0.2794)
			(end 0.12065 -0.2794)
			(stroke
				(width 0.1)
				(type default)
			)
			(layer "F.Fab")
		)
		(fp_line
			(start 0.12065 -0.2794)
			(end 0.12065 -0.3048)
			(stroke
				(width 0.1)
				(type default)
			)
			(layer "F.Fab")
		)
		(fp_line
			(start 0.12065 -0.3048)
			(end 0.67945 -0.3048)
			(stroke
				(width 0.1)
				(type default)
			)
			(layer "F.Fab")
		)
		(fp_line
			(start 0.67945 -0.3048)
			(end 0.67945 0.3048)
			(stroke
				(width 0.1)
				(type default)
			)
			(layer "F.Fab")
		)
		(fp_line
			(start -0.67945 -0.305054)
			(end -0.12065 -0.305054)
			(stroke
				(width 0.1)
				(type default)
			)
			(layer "F.Fab")
		)
		(fp_line
			(start -0.12065 -0.305054)
			(end -0.12065 -0.2794)
			(stroke
				(width 0.1)
				(type default)
			)
			(layer "F.Fab")
		)
		(pad "1" smd circle
			(at -0.40005 0 270)
			(size 0 0)
			(layers "F.Cu" "F.Mask" "F.Paste")
			(net "LED_RST_PLD_CPU1_DRAM_AB_N")
		)
		(pad "2" smd circle
			(at 0.40005 0 270)
			(size 0 0)
			(layers "F.Cu" "F.Mask" "F.Paste")
			(net "P3V3_AUX")
		)
	)
	(footprint ""
		(layer "F.Cu")
		(at 367.44783 -252.956314 -90)
		(property "Reference" "C1028"
			(at 0 0 270)
			(layer "F.SilkS")
			(hide yes)
			(effects
				(font
					(size 1.27 1.27)
				)
			)
		)
		(property "Value" ""
			(at 0 0 270)
			(layer "F.Fab")
			(effects
				(font
					(size 1.27 1.27)
				)
			)
		)
		(duplicate_pad_numbers_are_jumpers no)
		(fp_line
			(start -0.7874 0.4064)
			(end -0.7874 -0.4064)
			(stroke
				(width 0.1524)
				(type default)
			)
			(layer "F.SilkS")
		)
		(fp_line
			(start 0.7874 0.4064)
			(end -0.7874 0.4064)
			(stroke
				(width 0.1524)
				(type default)
			)
			(layer "F.SilkS")
		)
		(fp_line
			(start -0.7874 -0.4064)
			(end 0.7874 -0.4064)
			(stroke
				(width 0.1524)
				(type default)
			)
			(layer "F.SilkS")
		)
		(fp_line
			(start 0.7874 -0.4064)
			(end 0.7874 0.4064)
			(stroke
				(width 0.1524)
				(type default)
			)
			(layer "F.SilkS")
		)
		(fp_line
			(start -0.67945 0.3048)
			(end -0.67945 -0.305054)
			(stroke
				(width 0.1)
				(type default)
			)
			(layer "F.Fab")
		)
		(fp_line
			(start -0.12065 0.3048)
			(end -0.67945 0.3048)
			(stroke
				(width 0.1)
				(type default)
			)
			(layer "F.Fab")
		)
		(fp_line
			(start 0.120396 0.3048)
			(end 0.120396 0.2794)
			(stroke
				(width 0.1)
				(type default)
			)
			(layer "F.Fab")
		)
		(fp_line
			(start 0.67945 0.3048)
			(end 0.120396 0.3048)
			(stroke
				(width 0.1)
				(type default)
			)
			(layer "F.Fab")
		)
		(fp_line
			(start -0.12065 0.2794)
			(end -0.12065 0.3048)
			(stroke
				(width 0.1)
				(type default)
			)
			(layer "F.Fab")
		)
		(fp_line
			(start 0.120396 0.2794)
			(end -0.12065 0.2794)
			(stroke
				(width 0.1)
				(type default)
			)
			(layer "F.Fab")
		)
		(fp_line
			(start -0.12065 -0.2794)
			(end 0.12065 -0.2794)
			(stroke
				(width 0.1)
				(type default)
			)
			(layer "F.Fab")
		)
		(fp_line
			(start 0.12065 -0.2794)
			(end 0.12065 -0.3048)
			(stroke
				(width 0.1)
				(type default)
			)
			(layer "F.Fab")
		)
		(fp_line
			(start 0.12065 -0.3048)
			(end 0.67945 -0.3048)
			(stroke
				(width 0.1)
				(type default)
			)
			(layer "F.Fab")
		)
		(fp_line
			(start 0.67945 -0.3048)
			(end 0.67945 0.3048)
			(stroke
				(width 0.1)
				(type default)
			)
			(layer "F.Fab")
		)
		(fp_line
			(start -0.67945 -0.305054)
			(end -0.12065 -0.305054)
			(stroke
				(width 0.1)
				(type default)
			)
			(layer "F.Fab")
		)
		(fp_line
			(start -0.12065 -0.305054)
			(end -0.12065 -0.2794)
			(stroke
				(width 0.1)
				(type default)
			)
			(layer "F.Fab")
		)
		(pad "1" smd circle
			(at -0.40005 0 270)
			(size 0 0)
			(layers "F.Cu" "F.Mask" "F.Paste")
			(net "PVCCIN_CPU0")
		)
		(pad "2" smd circle
			(at 0.40005 0 270)
			(size 0 0)
			(layers "F.Cu" "F.Mask" "F.Paste")
			(net "GND")
		)
	)
	(footprint ""
		(layer "F.Cu")
		(at 404.2664 -385.84886)
		(property "Reference" "ME15"
			(at -9.652 -9.540748 0)
			(unlocked yes)
			(layer "F.SilkS")
			(effects
				(font
					(size 0.7874 0.5842)
					(thickness 0.1524)
				)
				(justify left)
			)
		)
		(property "Value" ""
			(at 0 0 0)
			(layer "F.Fab")
			(effects
				(font
					(size 1.27 1.27)
				)
			)
		)
		(duplicate_pad_numbers_are_jumpers no)
		(zone
			(layer "F.Cu")
			(hatch none 0.5)
			(connect_pads
				(clearance 0)
			)
			(min_thickness 0.25)
			(keepout
				(tracks allowed)
				(vias allowed)
				(pads allowed)
				(copperpour allowed)
				(footprints not_allowed)
			)
			(placement
				(enabled no)
				(sheetname "")
			)
			(fill
				(thermal_gap 0.5)
				(thermal_bridge_width 0.5)
				(island_removal_mode 0)
			)
			(polygon
				(pts
					(arc
						(start 414.26638 -385.84886)
						(mid 394.26642 -385.84886)
						(end 414.26638 -385.84886)
					)
				)
			)
		)
	)
	(footprint ""
		(layer "F.Cu")
		(at 288.9377 -406.81402 180)
		(property "Reference" "R4896"
			(at 0 0 180)
			(layer "F.SilkS")
			(hide yes)
			(effects
				(font
					(size 1.27 1.27)
				)
			)
		)
		(property "Value" ""
			(at 0 0 180)
			(layer "F.Fab")
			(effects
				(font
					(size 1.27 1.27)
				)
			)
		)
		(duplicate_pad_numbers_are_jumpers no)
		(fp_line
			(start 0.7874 0.4064)
			(end -0.7874 0.4064)
			(stroke
				(width 0.1524)
				(type default)
			)
			(layer "F.SilkS")
		)
		(fp_line
			(start 0.7874 -0.4064)
			(end 0.7874 0.4064)
			(stroke
				(width 0.1524)
				(type default)
			)
			(layer "F.SilkS")
		)
		(fp_line
			(start -0.7874 0.4064)
			(end -0.7874 -0.4064)
			(stroke
				(width 0.1524)
				(type default)
			)
			(layer "F.SilkS")
		)
		(fp_line
			(start -0.7874 -0.4064)
			(end 0.7874 -0.4064)
			(stroke
				(width 0.1524)
				(type default)
			)
			(layer "F.SilkS")
		)
		(fp_line
			(start 0.67945 0.3048)
			(end 0.120396 0.3048)
			(stroke
				(width 0.1)
				(type default)
			)
			(layer "F.Fab")
		)
		(fp_line
			(start 0.67945 -0.3048)
			(end 0.67945 0.3048)
			(stroke
				(width 0.1)
				(type default)
			)
			(layer "F.Fab")
		)
		(fp_line
			(start 0.12065 -0.2794)
			(end 0.12065 -0.3048)
			(stroke
				(width 0.1)
				(type default)
			)
			(layer "F.Fab")
		)
		(fp_line
			(start 0.12065 -0.3048)
			(end 0.67945 -0.3048)
			(stroke
				(width 0.1)
				(type default)
			)
			(layer "F.Fab")
		)
		(fp_line
			(start 0.120396 0.3048)
			(end 0.120396 0.2794)
			(stroke
				(width 0.1)
				(type default)
			)
			(layer "F.Fab")
		)
		(fp_line
			(start 0.120396 0.2794)
			(end -0.12065 0.2794)
			(stroke
				(width 0.1)
				(type default)
			)
			(layer "F.Fab")
		)
		(fp_line
			(start -0.12065 0.3048)
			(end -0.67945 0.3048)
			(stroke
				(width 0.1)
				(type default)
			)
			(layer "F.Fab")
		)
		(fp_line
			(start -0.12065 0.2794)
			(end -0.12065 0.3048)
			(stroke
				(width 0.1)
				(type default)
			)
			(layer "F.Fab")
		)
		(fp_line
			(start -0.12065 -0.2794)
			(end 0.12065 -0.2794)
			(stroke
				(width 0.1)
				(type default)
			)
			(layer "F.Fab")
		)
		(fp_line
			(start -0.12065 -0.305054)
			(end -0.12065 -0.2794)
			(stroke
				(width 0.1)
				(type default)
			)
			(layer "F.Fab")
		)
		(fp_line
			(start -0.67945 0.3048)
			(end -0.67945 -0.305054)
			(stroke
				(width 0.1)
				(type default)
			)
			(layer "F.Fab")
		)
		(fp_line
			(start -0.67945 -0.305054)
			(end -0.12065 -0.305054)
			(stroke
				(width 0.1)
				(type default)
			)
			(layer "F.Fab")
		)
		(pad "1" smd circle
			(at -0.40005 0 180)
			(size 0 0)
			(layers "F.Cu" "F.Mask" "F.Paste")
			(net "P12V_HSC_T_CRIT_N")
		)
		(pad "2" smd circle
			(at 0.40005 0 180)
			(size 0 0)
			(layers "F.Cu" "F.Mask" "F.Paste")
			(net "P12V_HSC_T_CRIT_R_N")
		)
	)
)
